# S9S_MB_2U (Grand Teton) — schematic netlist excerpt (pin names and nets, part order shuffled) for the footprints in the layout excerpt that follows; sources: Cadence DE-HDL packaged netlist, KiCad conversion of 03242023_DA0F0TMBIJ0_F0T_Motherboard_J_brd_V01_OCP.brd

C1911  Q_CAP  0.01UF 50V 10% X7R  pkg C0402  page 217 : A = P3V3_AUX_FPGA_VCCIO1 ; B = GND
C474  Q_CAP  47UF 4V 20% X6S  pkg C0805  page 78 : A = PVCCD_HV_CPU1 ; B = GND
R14  Q_RES  200 1% CHIP  pkg 0402LF  page 14 : A = SVID_ALERT0_CPU0_N ; B = SVID_ALERT0_CPU0_R_N

(kicad_pcb
	(version 20260206)
	(generator "pcbnew")
	(generator_version "10.0")
	(general
		(thickness 1.6)
		(legacy_teardrops no)
	)
	(paper "A4")
	(title_block
		(title "03242023_DA0F0TMBIJ0_F0T_Motherboard_J_brd_V01_OCP.brd")
		(comment 1 "Grand Teton / footprints 4880-4882 of 6105")
	)
	(layers
		(0 "F.Cu" signal "TOP")
		(4 "In1.Cu" signal "GND")
		(6 "In2.Cu" signal "IN1")
		(8 "In3.Cu" signal "GND1")
		(10 "In4.Cu" signal "IN2")
		(12 "In5.Cu" signal "GND2")
		(14 "In6.Cu" signal "IN3")
		(16 "In7.Cu" signal "GND3")
		(18 "In8.Cu" signal "VCC")
		(20 "In9.Cu" signal "VCC1")
		(22 "In10.Cu" signal "GND4")
		(24 "In11.Cu" signal "IN4")
		(26 "In12.Cu" signal "GND5")
		(28 "In13.Cu" signal "IN5")
		(30 "In14.Cu" signal "GND6")
		(32 "In15.Cu" signal "IN6")
		(34 "In16.Cu" signal "GND7")
		(2 "B.Cu" signal "BOTTOM")
		(9 "F.Adhes" user "F.Adhesive")
		(11 "B.Adhes" user "B.Adhesive")
		(13 "F.Paste" user "Package Geometry/Pastemask Top")
		(15 "B.Paste" user "Package Geometry/Pastemask Bottom")
		(5 "F.SilkS" user "Ref Des/Silkscreen Top")
		(7 "B.SilkS" user "Ref Des/Silkscreen Bottom")
		(1 "F.Mask" user "Board Geometry/Soldermask Top")
		(3 "B.Mask" user "Board Geometry/Soldermask Bottom")
		(17 "Dwgs.User" user "User.Drawings")
		(19 "Cmts.User" user "User.Comments")
		(21 "Eco1.User" user "User.Eco1")
		(23 "Eco2.User" user "User.Eco2")
		(25 "Edge.Cuts" user "Board Geometry/Outline")
		(27 "Margin" user)
		(31 "F.CrtYd" user "Package Geometry/Place Bound Top")
		(29 "B.CrtYd" user "Package Geometry/Place Bound Bottom")
		(35 "F.Fab" user "Ref Des/Assembly Top")
		(33 "B.Fab" user "Ref Des/Assembly Bottom")
	)
	(footprint ""
		(layer "B.Cu")
		(at 183.755538 -121.375424 -90)
		(property "Reference" "C1911"
			(at 0 0 90)
			(layer "B.SilkS")
			(hide yes)
			(effects
				(font
					(size 1.27 1.27)
				)
				(justify mirror)
			)
		)
		(property "Value" ""
			(at 0 0 90)
			(layer "B.Fab")
			(effects
				(font
					(size 1.27 1.27)
				)
				(justify mirror)
			)
		)
		(duplicate_pad_numbers_are_jumpers no)
		(fp_line
			(start -0.69215 0.2921)
			(end 0.69215 0.2921)
			(stroke
				(width 0.1524)
				(type default)
			)
			(layer "B.SilkS")
		)
		(fp_line
			(start 0.69215 0.2921)
			(end 0.69215 -0.2921)
			(stroke
				(width 0.1524)
				(type default)
			)
			(layer "B.SilkS")
		)
		(fp_line
			(start -0.69215 -0.2921)
			(end -0.69215 0.2921)
			(stroke
				(width 0.1524)
				(type default)
			)
			(layer "B.SilkS")
		)
		(fp_line
			(start 0.69215 -0.2921)
			(end -0.69215 -0.2921)
			(stroke
				(width 0.1524)
				(type default)
			)
			(layer "B.SilkS")
		)
		(fp_line
			(start -0.51435 0.2794)
			(end 0.51435 0.2794)
			(stroke
				(width 0.1)
				(type default)
			)
			(layer "B.Fab")
		)
		(fp_line
			(start 0.51435 0.2794)
			(end 0.51435 -0.2794)
			(stroke
				(width 0.1)
				(type default)
			)
			(layer "B.Fab")
		)
		(fp_line
			(start -0.51435 -0.2794)
			(end -0.51435 0.2794)
			(stroke
				(width 0.1)
				(type default)
			)
			(layer "B.Fab")
		)
		(fp_line
			(start 0.51435 -0.2794)
			(end -0.51435 -0.2794)
			(stroke
				(width 0.1)
				(type default)
			)
			(layer "B.Fab")
		)
		(pad "1" smd circle
			(at 0.40005 0 90)
			(size 0 0)
			(layers "B.Cu" "B.Mask" "B.Paste")
			(net "P3V3_AUX_FPGA_VCCIO1")
		)
		(pad "2" smd circle
			(at -0.40005 0 90)
			(size 0 0)
			(layers "B.Cu" "B.Mask" "B.Paste")
			(net "GND")
		)
		(zone
			(layer "B.Cu")
			(hatch none 0.5)
			(connect_pads
				(clearance 0)
			)
			(min_thickness 0.25)
			(keepout
				(tracks not_allowed)
				(vias allowed)
				(pads allowed)
				(copperpour not_allowed)
				(footprints allowed)
			)
			(placement
				(enabled no)
				(sheetname "")
			)
			(fill
				(thermal_gap 0.5)
				(thermal_bridge_width 0.5)
				(island_removal_mode 0)
			)
			(polygon
				(pts
					(xy 183.667908 -121.184924) (xy 183.609742 -121.276364) (xy 183.609742 -121.475754) (xy 183.667908 -121.565924)
					(xy 183.843168 -121.565924) (xy 183.901588 -121.475754) (xy 183.901588 -121.276364) (xy 183.843422 -121.184924)
				)
			)
		)
	)
	(footprint ""
		(layer "B.Cu")
		(at 303.554638 -194.72021 90)
		(property "Reference" "R14"
			(at 0 0 90)
			(layer "B.SilkS")
			(hide yes)
			(effects
				(font
					(size 1.27 1.27)
				)
				(justify mirror)
			)
		)
		(property "Value" ""
			(at 0 0 90)
			(layer "B.Fab")
			(effects
				(font
					(size 1.27 1.27)
				)
				(justify mirror)
			)
		)
		(duplicate_pad_numbers_are_jumpers no)
		(fp_line
			(start 0.7874 -0.4064)
			(end -0.7874 -0.4064)
			(stroke
				(width 0.1524)
				(type default)
			)
			(layer "B.SilkS")
		)
		(fp_line
			(start -0.7874 -0.4064)
			(end -0.7874 0.4064)
			(stroke
				(width 0.1524)
				(type default)
			)
			(layer "B.SilkS")
		)
		(fp_line
			(start 0.7874 0.4064)
			(end 0.7874 -0.4064)
			(stroke
				(width 0.1524)
				(type default)
			)
			(layer "B.SilkS")
		)
		(fp_line
			(start -0.7874 0.4064)
			(end 0.7874 0.4064)
			(stroke
				(width 0.1524)
				(type default)
			)
			(layer "B.SilkS")
		)
		(fp_line
			(start 0.67945 -0.305054)
			(end 0.12065 -0.305054)
			(stroke
				(width 0.1)
				(type default)
			)
			(layer "B.Fab")
		)
		(fp_line
			(start 0.12065 -0.305054)
			(end 0.12065 -0.2794)
			(stroke
				(width 0.1)
				(type default)
			)
			(layer "B.Fab")
		)
		(fp_line
			(start -0.12065 -0.3048)
			(end -0.67945 -0.3048)
			(stroke
				(width 0.1)
				(type default)
			)
			(layer "B.Fab")
		)
		(fp_line
			(start -0.67945 -0.3048)
			(end -0.67945 0.3048)
			(stroke
				(width 0.1)
				(type default)
			)
			(layer "B.Fab")
		)
		(fp_line
			(start 0.12065 -0.2794)
			(end -0.12065 -0.2794)
			(stroke
				(width 0.1)
				(type default)
			)
			(layer "B.Fab")
		)
		(fp_line
			(start -0.12065 -0.2794)
			(end -0.12065 -0.3048)
			(stroke
				(width 0.1)
				(type default)
			)
			(layer "B.Fab")
		)
		(fp_line
			(start 0.12065 0.2794)
			(end 0.12065 0.3048)
			(stroke
				(width 0.1)
				(type default)
			)
			(layer "B.Fab")
		)
		(fp_line
			(start -0.120396 0.2794)
			(end 0.12065 0.2794)
			(stroke
				(width 0.1)
				(type default)
			)
			(layer "B.Fab")
		)
		(fp_line
			(start 0.67945 0.3048)
			(end 0.67945 -0.305054)
			(stroke
				(width 0.1)
				(type default)
			)
			(layer "B.Fab")
		)
		(fp_line
			(start 0.12065 0.3048)
			(end 0.67945 0.3048)
			(stroke
				(width 0.1)
				(type default)
			)
			(layer "B.Fab")
		)
		(fp_line
			(start -0.120396 0.3048)
			(end -0.120396 0.2794)
			(stroke
				(width 0.1)
				(type default)
			)
			(layer "B.Fab")
		)
		(fp_line
			(start -0.67945 0.3048)
			(end -0.120396 0.3048)
			(stroke
				(width 0.1)
				(type default)
			)
			(layer "B.Fab")
		)
		(pad "1" smd circle
			(at 0.40005 0 270)
			(size 0 0)
			(layers "B.Cu" "B.Mask" "B.Paste")
			(net "SVID_ALERT0_CPU0_N")
		)
		(pad "2" smd circle
			(at -0.40005 0 270)
			(size 0 0)
			(layers "B.Cu" "B.Mask" "B.Paste")
			(net "SVID_ALERT0_CPU0_R_N")
		)
	)
	(footprint ""
		(layer "B.Cu")
		(at 103.979218 -241.20729 90)
		(property "Reference" "C474"
			(at 0 0 90)
			(layer "B.SilkS")
			(hide yes)
			(effects
				(font
					(size 1.27 1.27)
				)
				(justify mirror)
			)
		)
		(property "Value" ""
			(at 0 0 90)
			(layer "B.Fab")
			(effects
				(font
					(size 1.27 1.27)
				)
				(justify mirror)
			)
		)
		(duplicate_pad_numbers_are_jumpers no)
		(fp_line
			(start 1.524 -0.762)
			(end -1.524 -0.762)
			(stroke
				(width 0.1524)
				(type default)
			)
			(layer "B.SilkS")
		)
		(fp_line
			(start -1.524 -0.762)
			(end -1.524 0.762)
			(stroke
				(width 0.1524)
				(type default)
			)
			(layer "B.SilkS")
		)
		(fp_line
			(start 1.524 0.762)
			(end 1.524 -0.762)
			(stroke
				(width 0.1524)
				(type default)
			)
			(layer "B.SilkS")
		)
		(fp_line
			(start -1.524 0.762)
			(end 1.524 0.762)
			(stroke
				(width 0.1524)
				(type default)
			)
			(layer "B.SilkS")
		)
		(fp_line
			(start 1.1049 -0.724916)
			(end 1.1049 0.724916)
			(stroke
				(width 0.1)
				(type default)
			)
			(layer "B.Fab")
		)
		(fp_line
			(start -1.1049 -0.724916)
			(end 1.1049 -0.724916)
			(stroke
				(width 0.1)
				(type default)
			)
			(layer "B.Fab")
		)
		(fp_line
			(start 1.1049 0.724916)
			(end -1.1049 0.724916)
			(stroke
				(width 0.1)
				(type default)
			)
			(layer "B.Fab")
		)
		(fp_line
			(start -1.1049 0.724916)
			(end -1.1049 -0.724916)
			(stroke
				(width 0.1)
				(type default)
			)
			(layer "B.Fab")
		)
		(pad "1" smd rect
			(at 0.889 0 90)
			(size 1.016 1.27)
			(layers "B.Cu" "B.Mask" "B.Paste")
			(net "PVCCD_HV_CPU1")
		)
		(pad "2" smd rect
			(at -0.889 0 90)
			(size 1.016 1.27)
			(layers "B.Cu" "B.Mask" "B.Paste")
			(net "GND")
		)
	)
)
